(kicad_pcb
	(version 20260206)
	(generator "pcbnew")
	(generator_version "10.0")
	(general
		(thickness 1.6)
		(legacy_teardrops no)
	)
	(paper "A4")
	(title_block
		(title "Wiwynn_Tioga_Pass_MB.brd")
		(comment 1 "Tioga Pass / footprints 4637-4643 of 4770")
	)
	(layers
		(0 "F.Cu" signal "TOP")
		(4 "In1.Cu" signal "L2GND")
		(6 "In2.Cu" signal "L3")
		(8 "In3.Cu" signal "L4GND")
		(10 "In4.Cu" signal "L5")
		(12 "In5.Cu" signal "L6GND")
		(14 "In6.Cu" signal "L7VCC")
		(16 "In7.Cu" signal "L8VCC")
		(18 "In8.Cu" signal "L9GND")
		(20 "In9.Cu" signal "L10")
		(22 "In10.Cu" signal "L11GND")
		(24 "In11.Cu" signal "L12")
		(26 "In12.Cu" signal "L13GND")
		(2 "B.Cu" signal "BOTTOM")
		(9 "F.Adhes" user "F.Adhesive")
		(11 "B.Adhes" user "B.Adhesive")
		(13 "F.Paste" user "Package Geometry/Pastemask Top")
		(15 "B.Paste" user "Package Geometry/Pastemask Bottom")
		(5 "F.SilkS" user "Ref Des/Silkscreen Top")
		(7 "B.SilkS" user "Ref Des/Silkscreen Bottom")
		(1 "F.Mask" user "Board Geometry/Soldermask Top")
		(3 "B.Mask" user "Board Geometry/Soldermask Bottom")
		(17 "Dwgs.User" user "User.Drawings")
		(19 "Cmts.User" user "User.Comments")
		(21 "Eco1.User" user "User.Eco1")
		(23 "Eco2.User" user "User.Eco2")
		(25 "Edge.Cuts" user "Board Geometry/Outline")
		(27 "Margin" user)
		(31 "F.CrtYd" user "Package Geometry/Place Bound Top")
		(29 "B.CrtYd" user "Package Geometry/Place Bound Bottom")
		(35 "F.Fab" user "Ref Des/Assembly Top")
		(33 "B.Fab" user "Ref Des/Assembly Bottom")
	)
	(footprint ""
		(layer "B.Cu")
		(at 462.5975 -23.114 180)
		(property "Reference" "R6W21"
			(at 0.8382 -0.67818 180)
			(unlocked yes)
			(layer "B.SilkS")
			(effects
				(font
					(size 0.4064 0.254)
					(thickness 0.1524)
				)
				(justify left mirror)
			)
		)
		(property "Value" ""
			(at 0 0 0)
			(layer "B.Fab")
			(effects
				(font
					(size 1.27 1.27)
				)
				(justify mirror)
			)
		)
		(duplicate_pad_numbers_are_jumpers no)
		(fp_poly
			(pts
				(xy 0.2794 -0.1016) (xy -0.2794 -0.1016) (xy -0.2794 0.9906) (xy 0.2794 0.9906)
			)
			(stroke
				(width 0)
				(type default)
			)
			(fill no)
			(layer "B.CrtYd")
		)
		(fp_line
			(start 0.2794 0.9906)
			(end -0.2794 0.9906)
			(stroke
				(width 0.1)
				(type default)
			)
			(layer "B.Fab")
		)
		(fp_line
			(start 0.2794 -0.1016)
			(end 0.2794 0.9906)
			(stroke
				(width 0.1)
				(type default)
			)
			(layer "B.Fab")
		)
		(fp_line
			(start -0.2794 0.9906)
			(end -0.2794 -0.1016)
			(stroke
				(width 0.1)
				(type default)
			)
			(layer "B.Fab")
		)
		(fp_line
			(start -0.2794 -0.1016)
			(end 0.2794 -0.1016)
			(stroke
				(width 0.1)
				(type default)
			)
			(layer "B.Fab")
		)
		(pad "1" smd rect
			(at 0 0)
			(size 0.508 0.508)
			(layers "B.Cu" "B.Mask" "B.Paste")
			(net "P3V3_STBY")
		)
		(pad "2" smd rect
			(at 0 0.889)
			(size 0.508 0.508)
			(layers "B.Cu" "B.Mask" "B.Paste")
			(net "PU_ID_EEPROM_A0")
		)
		(zone
			(layer "B.Cu")
			(hatch none 0.5)
			(connect_pads
				(clearance 0)
			)
			(min_thickness 0.25)
			(keepout
				(tracks not_allowed)
				(vias allowed)
				(pads allowed)
				(copperpour not_allowed)
				(footprints allowed)
			)
			(placement
				(enabled no)
				(sheetname "")
			)
			(fill
				(thermal_gap 0.5)
				(thermal_bridge_width 0.5)
				(island_removal_mode 0)
			)
			(polygon
				(pts
					(xy 462.3435 -23.749) (xy 462.8515 -23.749) (xy 462.8515 -23.368) (xy 462.3435 -23.368)
				)
			)
		)
		(zone
			(layer "B.Cu")
			(hatch none 0.5)
			(connect_pads
				(clearance 0)
			)
			(min_thickness 0.25)
			(keepout
				(tracks allowed)
				(vias not_allowed)
				(pads allowed)
				(copperpour not_allowed)
				(footprints allowed)
			)
			(placement
				(enabled no)
				(sheetname "")
			)
			(fill
				(thermal_gap 0.5)
				(thermal_bridge_width 0.5)
				(island_removal_mode 0)
			)
			(polygon
				(pts
					(xy 462.3435 -23.368) (xy 462.8515 -23.368) (xy 462.8515 -23.749) (xy 462.3435 -23.749)
				)
			)
		)
	)
	(footprint ""
		(layer "B.Cu")
		(at 379.984 -140.589 180)
		(property "Reference" "C3L20"
			(at -3.10007 3.24612 270)
			(unlocked yes)
			(layer "B.SilkS")
			(effects
				(font
					(size 0.7874 0.5842)
					(thickness 0.1524)
				)
				(justify mirror)
			)
		)
		(property "Value" ""
			(at 0 0 0)
			(layer "B.Fab")
			(effects
				(font
					(size 1.27 1.27)
				)
				(justify mirror)
			)
		)
		(duplicate_pad_numbers_are_jumpers no)
		(fp_line
			(start 2.563114 1.633728)
			(end 1.6002 1.633728)
			(stroke
				(width 0.1524)
				(type default)
			)
			(layer "B.SilkS")
		)
		(fp_line
			(start 2.563114 -1.616456)
			(end 2.563114 1.633728)
			(stroke
				(width 0.1524)
				(type default)
			)
			(layer "B.SilkS")
		)
		(fp_line
			(start 2.286 7.366)
			(end 2.286 1.632712)
			(stroke
				(width 0.1524)
				(type default)
			)
			(layer "B.SilkS")
		)
		(fp_line
			(start 2.286 7.366)
			(end 1.60147 7.366)
			(stroke
				(width 0.1524)
				(type default)
			)
			(layer "B.SilkS")
		)
		(fp_line
			(start 1.6002 -1.616456)
			(end 2.563114 -1.616456)
			(stroke
				(width 0.1524)
				(type default)
			)
			(layer "B.SilkS")
		)
		(fp_line
			(start -1.6002 -1.616456)
			(end -2.504948 -1.616456)
			(stroke
				(width 0.1524)
				(type default)
			)
			(layer "B.SilkS")
		)
		(fp_line
			(start -2.286 7.366)
			(end -1.600708 7.366)
			(stroke
				(width 0.1524)
				(type default)
			)
			(layer "B.SilkS")
		)
		(fp_line
			(start -2.286 7.366)
			(end -2.286 1.63195)
			(stroke
				(width 0.1524)
				(type default)
			)
			(layer "B.SilkS")
		)
		(fp_line
			(start -2.504948 1.633728)
			(end -1.6002 1.633728)
			(stroke
				(width 0.1524)
				(type default)
			)
			(layer "B.SilkS")
		)
		(fp_line
			(start -2.504948 -1.616456)
			(end -2.504948 1.633728)
			(stroke
				(width 0.1524)
				(type default)
			)
			(layer "B.SilkS")
		)
		(fp_rect
			(start 2.286 7.366)
			(end -2.286 -0.254)
			(stroke
				(width 0)
				(type default)
			)
			(fill no)
			(layer "B.CrtYd")
		)
		(fp_line
			(start 2.286 7.366)
			(end 2.286 -0.254)
			(stroke
				(width 0.1)
				(type default)
			)
			(layer "B.Fab")
		)
		(fp_line
			(start 2.286 -0.254)
			(end -2.286 -0.254)
			(stroke
				(width 0.1)
				(type default)
			)
			(layer "B.Fab")
		)
		(fp_line
			(start -2.286 7.366)
			(end 2.286 7.366)
			(stroke
				(width 0.1)
				(type default)
			)
			(layer "B.Fab")
		)
		(fp_line
			(start -2.286 -0.254)
			(end -2.286 7.366)
			(stroke
				(width 0.1)
				(type default)
			)
			(layer "B.Fab")
		)
		(pad "1" smd rect
			(at 0 0)
			(size 2.54 3.048)
			(layers "B.Cu" "B.Mask" "B.Paste")
			(net "PVNN_PCH_STBY")
		)
		(pad "2" smd rect
			(at 0 7.112)
			(size 2.54 3.048)
			(layers "B.Cu" "B.Mask" "B.Paste")
			(net "GND")
		)
	)
	(footprint ""
		(layer "B.Cu")
		(at 49.4284 -86.67242)
		(property "Reference" "C9P3"
			(at 0 0 0)
			(layer "B.SilkS")
			(hide yes)
			(effects
				(font
					(size 1.27 1.27)
				)
				(justify mirror)
			)
		)
		(property "Value" ""
			(at 0 0 0)
			(layer "B.Fab")
			(effects
				(font
					(size 1.27 1.27)
				)
				(justify mirror)
			)
		)
		(duplicate_pad_numbers_are_jumpers no)
		(fp_poly
			(pts
				(xy 0.4953 -0.2032) (xy -0.4953 -0.2032) (xy -0.4953 1.6002) (xy 0.4953 1.6002)
			)
			(stroke
				(width 0)
				(type default)
			)
			(fill no)
			(layer "B.CrtYd")
		)
		(fp_line
			(start -0.4953 -0.2032)
			(end -0.4953 1.6002)
			(stroke
				(width 0.1)
				(type default)
			)
			(layer "B.Fab")
		)
		(fp_line
			(start -0.4953 1.6002)
			(end 0.4953 1.6002)
			(stroke
				(width 0.1)
				(type default)
			)
			(layer "B.Fab")
		)
		(fp_line
			(start 0.4953 -0.2032)
			(end -0.4953 -0.2032)
			(stroke
				(width 0.1)
				(type default)
			)
			(layer "B.Fab")
		)
		(fp_line
			(start 0.4953 1.6002)
			(end 0.4953 -0.2032)
			(stroke
				(width 0.1)
				(type default)
			)
			(layer "B.Fab")
		)
		(pad "1" smd rect
			(at 0 0 180)
			(size 0.762 0.889)
			(layers "B.Cu" "B.Mask" "B.Paste")
			(net "PVCCIN_CPU1")
		)
		(pad "2" smd rect
			(at 0 1.397 180)
			(size 0.762 0.889)
			(layers "B.Cu" "B.Mask" "B.Paste")
			(net "GND")
		)
		(zone
			(layer "B.Cu")
			(hatch none 0.5)
			(connect_pads
				(clearance 0)
			)
			(min_thickness 0.25)
			(keepout
				(tracks not_allowed)
				(vias allowed)
				(pads allowed)
				(copperpour not_allowed)
				(footprints allowed)
			)
			(placement
				(enabled no)
				(sheetname "")
			)
			(fill
				(thermal_gap 0.5)
				(thermal_bridge_width 0.5)
				(island_removal_mode 0)
			)
			(polygon
				(pts
					(xy 49.8094 -86.22792) (xy 49.0474 -86.22792) (xy 49.0474 -85.71992) (xy 49.8094 -85.71992)
				)
			)
		)
	)
	(footprint ""
		(layer "B.Cu")
		(at 49.4284 -70.993)
		(property "Reference" "C9P20"
			(at 0 0 0)
			(layer "B.SilkS")
			(hide yes)
			(effects
				(font
					(size 1.27 1.27)
				)
				(justify mirror)
			)
		)
		(property "Value" ""
			(at 0 0 0)
			(layer "B.Fab")
			(effects
				(font
					(size 1.27 1.27)
				)
				(justify mirror)
			)
		)
		(duplicate_pad_numbers_are_jumpers no)
		(fp_poly
			(pts
				(xy 0.4953 -0.2032) (xy -0.4953 -0.2032) (xy -0.4953 1.6002) (xy 0.4953 1.6002)
			)
			(stroke
				(width 0)
				(type default)
			)
			(fill no)
			(layer "B.CrtYd")
		)
		(fp_line
			(start -0.4953 -0.2032)
			(end -0.4953 1.6002)
			(stroke
				(width 0.1)
				(type default)
			)
			(layer "B.Fab")
		)
		(fp_line
			(start -0.4953 1.6002)
			(end 0.4953 1.6002)
			(stroke
				(width 0.1)
				(type default)
			)
			(layer "B.Fab")
		)
		(fp_line
			(start 0.4953 -0.2032)
			(end -0.4953 -0.2032)
			(stroke
				(width 0.1)
				(type default)
			)
			(layer "B.Fab")
		)
		(fp_line
			(start 0.4953 1.6002)
			(end 0.4953 -0.2032)
			(stroke
				(width 0.1)
				(type default)
			)
			(layer "B.Fab")
		)
		(pad "1" smd rect
			(at 0 0 180)
			(size 0.762 0.889)
			(layers "B.Cu" "B.Mask" "B.Paste")
			(net "PVCCIN_CPU1")
		)
		(pad "2" smd rect
			(at 0 1.397 180)
			(size 0.762 0.889)
			(layers "B.Cu" "B.Mask" "B.Paste")
			(net "GND")
		)
		(zone
			(layer "B.Cu")
			(hatch none 0.5)
			(connect_pads
				(clearance 0)
			)
			(min_thickness 0.25)
			(keepout
				(tracks not_allowed)
				(vias allowed)
				(pads allowed)
				(copperpour not_allowed)
				(footprints allowed)
			)
			(placement
				(enabled no)
				(sheetname "")
			)
			(fill
				(thermal_gap 0.5)
				(thermal_bridge_width 0.5)
				(island_removal_mode 0)
			)
			(polygon
				(pts
					(xy 49.8094 -70.5485) (xy 49.0474 -70.5485) (xy 49.0474 -70.0405) (xy 49.8094 -70.0405)
				)
			)
		)
	)
	(footprint ""
		(layer "B.Cu")
		(at 420.624 -81.4705 180)
		(property "Reference" "C2P1"
			(at 0 0 0)
			(layer "B.SilkS")
			(hide yes)
			(effects
				(font
					(size 1.27 1.27)
				)
				(justify mirror)
			)
		)
		(property "Value" ""
			(at 0 0 0)
			(layer "B.Fab")
			(effects
				(font
					(size 1.27 1.27)
				)
				(justify mirror)
			)
		)
		(duplicate_pad_numbers_are_jumpers no)
		(fp_poly
			(pts
				(xy -0.3048 -0.1016) (xy -0.3048 0.9906) (xy 0.3048 0.9906) (xy 0.3048 -0.1016)
			)
			(stroke
				(width 0)
				(type default)
			)
			(fill no)
			(layer "B.CrtYd")
		)
		(fp_line
			(start 0.3048 0.9906)
			(end -0.3048 0.9906)
			(stroke
				(width 0.1)
				(type default)
			)
			(layer "B.Fab")
		)
		(fp_line
			(start 0.3048 -0.1016)
			(end 0.3048 0.9906)
			(stroke
				(width 0.1)
				(type default)
			)
			(layer "B.Fab")
		)
		(fp_line
			(start -0.3048 0.9906)
			(end -0.3048 -0.1016)
			(stroke
				(width 0.1)
				(type default)
			)
			(layer "B.Fab")
		)
		(fp_line
			(start -0.3048 -0.1016)
			(end 0.3048 -0.1016)
			(stroke
				(width 0.1)
				(type default)
			)
			(layer "B.Fab")
		)
		(pad "1" smd rect
			(at 0 0)
			(size 0.508 0.508)
			(layers "B.Cu" "B.Mask" "B.Paste")
			(net "P3V3_STBY")
		)
		(pad "2" smd rect
			(at 0 0.889)
			(size 0.508 0.508)
			(layers "B.Cu" "B.Mask" "B.Paste")
			(net "GND")
		)
		(zone
			(layer "B.Cu")
			(hatch none 0.5)
			(connect_pads
				(clearance 0)
			)
			(min_thickness 0.25)
			(keepout
				(tracks not_allowed)
				(vias allowed)
				(pads allowed)
				(copperpour not_allowed)
				(footprints allowed)
			)
			(placement
				(enabled no)
				(sheetname "")
			)
			(fill
				(thermal_gap 0.5)
				(thermal_bridge_width 0.5)
				(island_removal_mode 0)
			)
			(polygon
				(pts
					(xy 420.37 -82.1055) (xy 420.878 -82.1055) (xy 420.878 -81.7245) (xy 420.37 -81.7245)
				)
			)
		)
		(zone
			(layer "B.Cu")
			(hatch none 0.5)
			(connect_pads
				(clearance 0)
			)
			(min_thickness 0.25)
			(keepout
				(tracks allowed)
				(vias not_allowed)
				(pads allowed)
				(copperpour not_allowed)
				(footprints allowed)
			)
			(placement
				(enabled no)
				(sheetname "")
			)
			(fill
				(thermal_gap 0.5)
				(thermal_bridge_width 0.5)
				(island_removal_mode 0)
			)
			(polygon
				(pts
					(xy 420.37 -81.7245) (xy 420.878 -81.7245) (xy 420.878 -82.1055) (xy 420.37 -82.1055)
				)
			)
		)
	)
	(footprint ""
		(layer "B.Cu")
		(at 420.624 -155.829 90)
		(property "Reference" "C2L3"
			(at 0 0 90)
			(layer "B.SilkS")
			(hide yes)
			(effects
				(font
					(size 1.27 1.27)
				)
				(justify mirror)
			)
		)
		(property "Value" ""
			(at 0 0 90)
			(layer "B.Fab")
			(effects
				(font
					(size 1.27 1.27)
				)
				(justify mirror)
			)
		)
		(duplicate_pad_numbers_are_jumpers no)
		(fp_poly
			(pts
				(xy -0.3048 -0.1016) (xy -0.3048 0.9906) (xy 0.3048 0.9906) (xy 0.3048 -0.1016)
			)
			(stroke
				(width 0)
				(type default)
			)
			(fill no)
			(layer "B.CrtYd")
		)
		(fp_line
			(start 0.3048 -0.1016)
			(end 0.3048 0.9906)
			(stroke
				(width 0.1)
				(type default)
			)
			(layer "B.Fab")
		)
		(fp_line
			(start -0.3048 -0.1016)
			(end 0.3048 -0.1016)
			(stroke
				(width 0.1)
				(type default)
			)
			(layer "B.Fab")
		)
		(fp_line
			(start 0.3048 0.9906)
			(end -0.3048 0.9906)
			(stroke
				(width 0.1)
				(type default)
			)
			(layer "B.Fab")
		)
		(fp_line
			(start -0.3048 0.9906)
			(end -0.3048 -0.1016)
			(stroke
				(width 0.1)
				(type default)
			)
			(layer "B.Fab")
		)
		(pad "1" smd rect
			(at 0 0 270)
			(size 0.508 0.508)
			(layers "B.Cu" "B.Mask" "B.Paste")
			(net "SATA6G_PCH_PCIE_UP_SATA_RXN<3>")
		)
		(pad "2" smd rect
			(at 0 0.889 270)
			(size 0.508 0.508)
			(layers "B.Cu" "B.Mask" "B.Paste")
			(net "SATA6G_P3_RX_C_DN")
		)
		(zone
			(layer "B.Cu")
			(hatch none 0.5)
			(connect_pads
				(clearance 0)
			)
			(min_thickness 0.25)
			(keepout
				(tracks allowed)
				(vias not_allowed)
				(pads allowed)
				(copperpour not_allowed)
				(footprints allowed)
			)
			(placement
				(enabled no)
				(sheetname "")
			)
			(fill
				(thermal_gap 0.5)
				(thermal_bridge_width 0.5)
				(island_removal_mode 0)
			)
			(polygon
				(pts
					(xy 420.878 -156.083) (xy 420.878 -155.575) (xy 421.259 -155.575) (xy 421.259 -156.083)
				)
			)
		)
		(zone
			(layer "B.Cu")
			(hatch none 0.5)
			(connect_pads
				(clearance 0)
			)
			(min_thickness 0.25)
			(keepout
				(tracks not_allowed)
				(vias allowed)
				(pads allowed)
				(copperpour not_allowed)
				(footprints allowed)
			)
			(placement
				(enabled no)
				(sheetname "")
			)
			(fill
				(thermal_gap 0.5)
				(thermal_bridge_width 0.5)
				(island_removal_mode 0)
			)
			(polygon
				(pts
					(xy 421.259 -156.083) (xy 421.259 -155.575) (xy 420.878 -155.575) (xy 420.878 -156.083)
				)
			)
		)
	)
	(footprint ""
		(layer "B.Cu")
		(at 391.8839 -103.3272 90)
		(property "Reference" "C2N25"
			(at 0 0 90)
			(layer "B.SilkS")
			(hide yes)
			(effects
				(font
					(size 1.27 1.27)
				)
				(justify mirror)
			)
		)
		(property "Value" ""
			(at 0 0 90)
			(layer "B.Fab")
			(effects
				(font
					(size 1.27 1.27)
				)
				(justify mirror)
			)
		)
		(duplicate_pad_numbers_are_jumpers no)
		(fp_rect
			(start 0.2794 0.9144)
			(end -0.2794 -0.1143)
			(stroke
				(width 0)
				(type default)
			)
			(fill no)
			(layer "B.CrtYd")
		)
		(fp_line
			(start 0.2794 -0.1143)
			(end -0.2794 -0.1143)
			(stroke
				(width 0.1)
				(type default)
			)
			(layer "B.Fab")
		)
		(fp_line
			(start -0.2794 -0.1143)
			(end -0.2794 0.9144)
			(stroke
				(width 0.1)
				(type default)
			)
			(layer "B.Fab")
		)
		(fp_line
			(start 0.2794 0.9144)
			(end 0.2794 -0.1143)
			(stroke
				(width 0.1)
				(type default)
			)
			(layer "B.Fab")
		)
		(fp_line
			(start -0.2794 0.9144)
			(end 0.2794 0.9144)
			(stroke
				(width 0.1)
				(type default)
			)
			(layer "B.Fab")
		)
		(pad "1" smd custom
			(at 0 0)
			(size 0.10414 0.10414)
			(layers "B.Cu" "B.Mask" "B.Paste")
			(net "P3V3_STBY")
			(options
				(clearance outline)
				(anchor circle)
			)
			(primitives
				(gr_poly
					(pts
						(xy -0.20828 -0.08636) (xy -0.20828 0.08636) (xy -0.08636 0.20828) (xy 0.086614 0.20828) (xy 0.20828 0.086614)
						(xy 0.20828 -0.08636) (xy 0.08636 -0.20828) (xy -0.08636 -0.20828)
					)
					(width 0)
					(fill yes)
				)
			)
		)
		(pad "2" smd custom
			(at 0 0.8001)
			(size 0.10414 0.10414)
			(layers "B.Cu" "B.Mask" "B.Paste")
			(net "GND")
			(options
				(clearance outline)
				(anchor circle)
			)
			(primitives
				(gr_poly
					(pts
						(xy -0.20828 -0.08636) (xy -0.20828 0.08636) (xy -0.08636 0.20828) (xy 0.086614 0.20828) (xy 0.20828 0.086614)
						(xy 0.20828 -0.08636) (xy 0.08636 -0.20828) (xy -0.08636 -0.20828)
					)
					(width 0)
					(fill yes)
				)
			)
		)
		(zone
			(layer "B.Cu")
			(hatch none 0.5)
			(connect_pads
				(clearance 0)
			)
			(min_thickness 0.25)
			(keepout
				(tracks allowed)
				(vias not_allowed)
				(pads allowed)
				(copperpour not_allowed)
				(footprints allowed)
			)
			(placement
				(enabled no)
				(sheetname "")
			)
			(fill
				(thermal_gap 0.5)
				(thermal_bridge_width 0.5)
				(island_removal_mode 0)
			)
			(polygon
				(pts
					(xy 392.09345 -103.41483) (xy 392.47445 -103.41483) (xy 392.47445 -103.23957) (xy 392.09345 -103.239316)
				)
			)
		)
		(zone
			(layer "B.Cu")
			(hatch none 0.5)
			(connect_pads
				(clearance 0)
			)
			(min_thickness 0.25)
			(keepout
				(tracks not_allowed)
				(vias allowed)
				(pads allowed)
				(copperpour not_allowed)
				(footprints allowed)
			)
			(placement
				(enabled no)
				(sheetname "")
			)
			(fill
				(thermal_gap 0.5)
				(thermal_bridge_width 0.5)
				(island_removal_mode 0)
			)
			(polygon
				(pts
					(xy 392.09345 -103.41483) (xy 392.47445 -103.41483) (xy 392.47445 -103.23957) (xy 392.09345 -103.239316)
				)
			)
		)
	)
)
